# T6G (Grand Teton) — schematic netlist excerpt (pin names and nets, part order shuffled) for the footprints in the layout excerpt that follows; sources: Cadence DE-HDL packaged netlist, KiCad conversion of 04192023_DAF0TMB3IC0_F0TG_MB_C_brd_V02_OCP.brd

PU289  MP5990GMA1111Z  MP5990GMA-1111-Z IC  pkg LGA45_TH_0-45_7X5  page 262
  VIN1  = P12V_PSU
  VIN2  = P12V_PSU
  VIN3  = P12V_PSU
  VIN4  = P12V_PSU
  VIN5  = P12V_PSU
  VIN6  = P12V_PSU
  VIN7  = P12V_PSU
  VIN8  = P12V_PSU
  VINSEN  = HSC_VSENSE
  \alt#\  = IRQ_SML1_PMBUS_ALERT
  SCL  = SMB_SML1_PMBUS_HSC_L_SCL
  SDA  = SMB_SML1_PMBUS_HSC_R_SDA
  \pg||ocw#\  = MB0_P12V_STBY_PWRGD
  \vin_uvw#\  = HSC_VIN_UVW_N
  VTEMP  = HSC_VTEMP
  SS  = HSC_SS
  VDD33_1  = HSC_VDD_R
  GND1  = AGND_HSC
  VDD18  = HSC_VDD18
  CS  = HSC_CS
  IMON  = HSC_IMON
  OCREF  = HSC_OCREF
  ADDR  = HSC_ADDR
  VOSEN  = HSC_VOSEN
  SCREF_OCWREF  = HSC_SCREF
  EN  = HSC_EN_R
  VOUT1  = P12V_AUX
  VOUT2  = P12V_AUX
  VOUT3  = P12V_AUX
  VOUT4  = P12V_AUX
  VOUT5  = P12V_AUX
  VOUT6  = P12V_AUX
  VOUT7  = P12V_AUX
  VOUT8  = P12V_AUX
  VOUT9  = P12V_AUX
  VOUT10  = P12V_AUX
  D_OC  = HSC_D_OC_R
  \on\  = HSC_ON_R
  GOK  = HSC_FAULT
  FLT_TYPE  = HSC_FLT_TYPE
  MODE  = HSC_MODE
  VIN9  = P12V_PSU
  VIN10  = P12V_PSU
  GND2  = AGND_HSC
  VDD33_2  = HSC_VDD_R

(kicad_pcb
	(version 20260206)
	(generator "pcbnew")
	(generator_version "10.0")
	(general
		(thickness 1.6)
		(legacy_teardrops no)
	)
	(paper "A4")
	(title_block
		(title "04192023_DAF0TMB3IC0_F0TG_MB_C_brd_V02_OCP.brd")
		(comment 1 "Grand Teton / footprint 1268 of 8354 (PU289), pads 1-45 of 45")
	)
	(layers
		(0 "F.Cu" signal "TOP")
		(4 "In1.Cu" signal "GND")
		(6 "In2.Cu" signal "IN1")
		(8 "In3.Cu" signal "GND1")
		(10 "In4.Cu" signal "IN2")
		(12 "In5.Cu" signal "GND2")
		(14 "In6.Cu" signal "IN3")
		(16 "In7.Cu" signal "GND3")
		(18 "In8.Cu" signal "VCC")
		(20 "In9.Cu" signal "VCC1")
		(22 "In10.Cu" signal "GND4")
		(24 "In11.Cu" signal "IN4")
		(26 "In12.Cu" signal "GND5")
		(28 "In13.Cu" signal "IN5")
		(30 "In14.Cu" signal "GND6")
		(32 "In15.Cu" signal "IN6")
		(34 "In16.Cu" signal "GND7")
		(2 "B.Cu" signal "BOTTOM")
		(9 "F.Adhes" user "F.Adhesive")
		(11 "B.Adhes" user "B.Adhesive")
		(13 "F.Paste" user "Package Geometry/Pastemask Top")
		(15 "B.Paste" user "Package Geometry/Pastemask Bottom")
		(5 "F.SilkS" user "Ref Des/Silkscreen Top")
		(7 "B.SilkS" user "Ref Des/Silkscreen Bottom")
		(1 "F.Mask" user "Board Geometry/Soldermask Top")
		(3 "B.Mask" user "Board Geometry/Soldermask Bottom")
		(17 "Dwgs.User" user "User.Drawings")
		(19 "Cmts.User" user "User.Comments")
		(21 "Eco1.User" user "User.Eco1")
		(23 "Eco2.User" user "User.Eco2")
		(25 "Edge.Cuts" user "Board Geometry/Outline")
		(27 "Margin" user)
		(31 "F.CrtYd" user "Package Geometry/Place Bound Top")
		(29 "B.CrtYd" user "Package Geometry/Place Bound Bottom")
		(35 "F.Fab" user "Ref Des/Assembly Top")
		(33 "B.Fab" user "Ref Des/Assembly Bottom")
	)
	(footprint ""
		(layer "F.Cu")
		(at 185.278522 -401.919694 -90)
		(property "Reference" "PU289"
			(at 3.212592 -5.588762 0)
			(unlocked yes)
			(layer "F.SilkS")
			(effects
				(font
					(size 0.7874 0.5842)
					(thickness 0.1524)
				)
			)
		)
		(property "Value" ""
			(at 0 0 270)
			(layer "F.Fab")
			(effects
				(font
					(size 1.27 1.27)
				)
			)
		)
		(duplicate_pad_numbers_are_jumpers no)
		(pad "1" smd rect
			(at -2.237486 -2.70002)
			(size 0.2286 0.381)
			(layers "F.Cu" "F.Mask" "F.Paste")
			(net "P12V_PSU")
		)
		(pad "2" smd rect
			(at -2.237486 -2.249932)
			(size 0.2286 0.381)
			(layers "F.Cu" "F.Mask" "F.Paste")
			(net "P12V_PSU")
		)
		(pad "3" smd rect
			(at -2.237486 -1.800098)
			(size 0.2286 0.381)
			(layers "F.Cu" "F.Mask" "F.Paste")
			(net "P12V_PSU")
		)
		(pad "4" smd rect
			(at -2.237486 -1.35001)
			(size 0.2286 0.381)
			(layers "F.Cu" "F.Mask" "F.Paste")
			(net "P12V_PSU")
		)
		(pad "5" smd rect
			(at -2.237486 -0.899922)
			(size 0.2286 0.381)
			(layers "F.Cu" "F.Mask" "F.Paste")
			(net "P12V_PSU")
		)
		(pad "6" smd rect
			(at -2.237486 -0.450088)
			(size 0.2286 0.381)
			(layers "F.Cu" "F.Mask" "F.Paste")
			(net "P12V_PSU")
		)
		(pad "7" smd rect
			(at -2.237486 0)
			(size 0.2286 0.381)
			(layers "F.Cu" "F.Mask" "F.Paste")
			(net "P12V_PSU")
		)
		(pad "8" smd rect
			(at -2.237486 0.450088)
			(size 0.2286 0.381)
			(layers "F.Cu" "F.Mask" "F.Paste")
			(net "P12V_PSU")
		)
		(pad "9" smd rect
			(at -2.237486 0.899922)
			(size 0.2286 0.381)
			(layers "F.Cu" "F.Mask" "F.Paste")
			(net "HSC_VSENSE")
		)
		(pad "10" smd rect
			(at -2.237486 1.35001)
			(size 0.2286 0.381)
			(layers "F.Cu" "F.Mask" "F.Paste")
			(net "IRQ_SML1_PMBUS_ALERT")
		)
		(pad "11" smd rect
			(at -2.237486 1.800098)
			(size 0.2286 0.381)
			(layers "F.Cu" "F.Mask" "F.Paste")
			(net "SMB_SML1_PMBUS_HSC_L_SCL")
		)
		(pad "12" smd rect
			(at -2.237486 2.249932)
			(size 0.2286 0.381)
			(layers "F.Cu" "F.Mask" "F.Paste")
			(net "SMB_SML1_PMBUS_HSC_R_SDA")
		)
		(pad "13" smd rect
			(at -2.237486 2.70002)
			(size 0.2286 0.381)
			(layers "F.Cu" "F.Mask" "F.Paste")
			(net "MB0_P12V_STBY_PWRGD")
		)
		(pad "14" smd rect
			(at -1.575054 3.237484 270)
			(size 0.2286 0.381)
			(layers "F.Cu" "F.Mask" "F.Paste")
			(net "HSC_VIN_UVW_N")
		)
		(pad "15" smd rect
			(at -1.124966 3.237484 270)
			(size 0.2286 0.381)
			(layers "F.Cu" "F.Mask" "F.Paste")
			(net "HSC_VTEMP")
		)
		(pad "16" smd rect
			(at -0.674878 3.237484 270)
			(size 0.2286 0.381)
			(layers "F.Cu" "F.Mask" "F.Paste")
			(net "HSC_SS")
		)
		(pad "17" smd rect
			(at -0.225044 3.237484 270)
			(size 0.2286 0.381)
			(layers "F.Cu" "F.Mask" "F.Paste")
			(net "HSC_VDD_R")
		)
		(pad "18" smd rect
			(at 0.225044 3.237484 270)
			(size 0.2286 0.381)
			(layers "F.Cu" "F.Mask" "F.Paste")
			(net "AGND_HSC")
		)
		(pad "19" smd rect
			(at 0.674878 3.237484 270)
			(size 0.2286 0.381)
			(layers "F.Cu" "F.Mask" "F.Paste")
			(net "HSC_VDD18")
		)
		(pad "20" smd rect
			(at 1.124966 3.237484 270)
			(size 0.2286 0.381)
			(layers "F.Cu" "F.Mask" "F.Paste")
			(net "HSC_CS")
		)
		(pad "21" smd rect
			(at 1.575054 3.237484 270)
			(size 0.2286 0.381)
			(layers "F.Cu" "F.Mask" "F.Paste")
			(net "HSC_IMON")
		)
		(pad "22" smd rect
			(at 2.237486 2.70002)
			(size 0.2286 0.381)
			(layers "F.Cu" "F.Mask" "F.Paste")
			(net "HSC_OCREF")
		)
		(pad "23" smd rect
			(at 2.237486 2.249932)
			(size 0.2286 0.381)
			(layers "F.Cu" "F.Mask" "F.Paste")
			(net "HSC_ADDR")
		)
		(pad "24" smd rect
			(at 2.237486 1.800098)
			(size 0.2286 0.381)
			(layers "F.Cu" "F.Mask" "F.Paste")
			(net "HSC_VOSEN")
		)
		(pad "25" smd rect
			(at 2.237486 1.35001)
			(size 0.2286 0.381)
			(layers "F.Cu" "F.Mask" "F.Paste")
			(net "HSC_SCREF")
		)
		(pad "26" smd rect
			(at 2.237486 0.899922)
			(size 0.2286 0.381)
			(layers "F.Cu" "F.Mask" "F.Paste")
			(net "HSC_EN_R")
		)
		(pad "27" smd rect
			(at 2.237486 0.450088)
			(size 0.2286 0.381)
			(layers "F.Cu" "F.Mask" "F.Paste")
			(net "P12V_AUX")
		)
		(pad "28" smd rect
			(at 2.237486 0)
			(size 0.2286 0.381)
			(layers "F.Cu" "F.Mask" "F.Paste")
			(net "P12V_AUX")
		)
		(pad "29" smd rect
			(at 2.237486 -0.450088)
			(size 0.2286 0.381)
			(layers "F.Cu" "F.Mask" "F.Paste")
			(net "P12V_AUX")
		)
		(pad "30" smd rect
			(at 2.237486 -0.899922)
			(size 0.2286 0.381)
			(layers "F.Cu" "F.Mask" "F.Paste")
			(net "P12V_AUX")
		)
		(pad "31" smd rect
			(at 2.237486 -1.35001)
			(size 0.2286 0.381)
			(layers "F.Cu" "F.Mask" "F.Paste")
			(net "P12V_AUX")
		)
		(pad "32" smd rect
			(at 2.237486 -1.800098)
			(size 0.2286 0.381)
			(layers "F.Cu" "F.Mask" "F.Paste")
			(net "P12V_AUX")
		)
		(pad "33" smd rect
			(at 2.237486 -2.249932)
			(size 0.2286 0.381)
			(layers "F.Cu" "F.Mask" "F.Paste")
			(net "P12V_AUX")
		)
		(pad "34" smd rect
			(at 2.237486 -2.70002)
			(size 0.2286 0.381)
			(layers "F.Cu" "F.Mask" "F.Paste")
			(net "P12V_AUX")
		)
		(pad "35" smd rect
			(at 1.575054 -3.237484 270)
			(size 0.2286 0.381)
			(layers "F.Cu" "F.Mask" "F.Paste")
			(net "P12V_AUX")
		)
		(pad "36" smd rect
			(at 1.124966 -3.237484 270)
			(size 0.2286 0.381)
			(layers "F.Cu" "F.Mask" "F.Paste")
			(net "P12V_AUX")
		)
		(pad "37" smd rect
			(at 0.674878 -3.237484 270)
			(size 0.2286 0.381)
			(layers "F.Cu" "F.Mask" "F.Paste")
			(net "HSC_D_OC_R")
		)
		(pad "38" smd rect
			(at 0.225044 -3.237484 270)
			(size 0.2286 0.381)
			(layers "F.Cu" "F.Mask" "F.Paste")
			(net "HSC_ON_R")
		)
		(pad "39" smd rect
			(at -0.225044 -3.237484 270)
			(size 0.2286 0.381)
			(layers "F.Cu" "F.Mask" "F.Paste")
			(net "HSC_FAULT")
		)
		(pad "40" smd rect
			(at -0.674878 -3.237484 270)
			(size 0.2286 0.381)
			(layers "F.Cu" "F.Mask" "F.Paste")
			(net "HSC_FLT_TYPE")
		)
		(pad "41" smd rect
			(at -1.124966 -3.237484 270)
			(size 0.2286 0.381)
			(layers "F.Cu" "F.Mask" "F.Paste")
			(net "HSC_MODE")
		)
		(pad "42" smd rect
			(at -1.575054 -3.237484 270)
			(size 0.2286 0.381)
			(layers "F.Cu" "F.Mask" "F.Paste")
			(net "P12V_PSU")
		)
		(pad "43" smd rect
			(at 0 -0.999998 270)
			(size 3.4036 3.4036)
			(layers "F.Cu" "F.Mask" "F.Paste")
			(net "P12V_PSU")
		)
		(pad "44" smd rect
			(at -1.124966 1.89992 270)
			(size 1.1684 1.6002)
			(layers "F.Cu" "F.Mask" "F.Paste")
			(net "AGND_HSC")
		)
		(pad "45" smd rect
			(at 1.124966 1.89992 270)
			(size 1.1684 1.6002)
			(layers "F.Cu" "F.Mask" "F.Paste")
			(net "HSC_VDD_R")
		)
	)
)
